(kicad_pcb
	(version 20260206)
	(generator "pcbnew")
	(generator_version "10.0")
	(general
		(thickness 1.6)
		(legacy_teardrops no)
	)
	(paper "A4")
	(title_block
		(title "Bryce Canyon_F.DPB_16315-1-OCP.brd")
		(comment 1 "Bryce Canyon / footprints 1371-1378 of 2223")
	)
	(layers
		(0 "F.Cu" signal "TOP")
		(4 "In1.Cu" signal "L2GND")
		(6 "In2.Cu" signal "L3")
		(8 "In3.Cu" signal "L4GND")
		(10 "In4.Cu" signal "L5")
		(12 "In5.Cu" signal "L6VCC")
		(14 "In6.Cu" signal "L7VCC")
		(16 "In7.Cu" signal "L8")
		(18 "In8.Cu" signal "L9GND")
		(20 "In9.Cu" signal "L10")
		(22 "In10.Cu" signal "L11GND")
		(2 "B.Cu" signal "BOTTOM")
		(9 "F.Adhes" user "F.Adhesive")
		(11 "B.Adhes" user "B.Adhesive")
		(13 "F.Paste" user "Package Geometry/Pastemask Top")
		(15 "B.Paste" user "Package Geometry/Pastemask Bottom")
		(5 "F.SilkS" user "Ref Des/Silkscreen Top")
		(7 "B.SilkS" user "Ref Des/Silkscreen Bottom")
		(1 "F.Mask" user "Board Geometry/Soldermask Top")
		(3 "B.Mask" user "Board Geometry/Soldermask Bottom")
		(17 "Dwgs.User" user "User.Drawings")
		(19 "Cmts.User" user "User.Comments")
		(21 "Eco1.User" user "User.Eco1")
		(23 "Eco2.User" user "User.Eco2")
		(25 "Edge.Cuts" user "Board Geometry/Outline")
		(27 "Margin" user)
		(31 "F.CrtYd" user "Package Geometry/Place Bound Top")
		(29 "B.CrtYd" user "Package Geometry/Place Bound Bottom")
		(35 "F.Fab" user "Ref Des/Assembly Top")
		(33 "B.Fab" user "Ref Des/Assembly Bottom")
	)
	(footprint ""
		(layer "F.Cu")
		(at 235.331 -394.1318 180)
		(property "Reference" "R1143"
			(at 0 0 180)
			(layer "F.SilkS")
			(hide yes)
			(effects
				(font
					(size 1.27 1.27)
				)
			)
		)
		(property "Value" "0R2J-2-GP"
			(at 0.064008 -3.993896 180)
			(unlocked yes)
			(layer "F.Fab")
			(hide yes)
			(effects
				(font
					(size 1.016 1.016)
					(thickness 0.1524)
				)
			)
		)
		(property "Device Type" "R402H16"
			(at 0.064008 -5.517896 180)
			(unlocked yes)
			(layer "F.Fab")
			(hide yes)
			(effects
				(font
					(size 1.016 1.016)
					(thickness 0.1524)
				)
			)
		)
		(duplicate_pad_numbers_are_jumpers no)
		(fp_line
			(start 0.508 -0.9398)
			(end -0.508 -0.9398)
			(stroke
				(width 0.1524)
				(type default)
			)
			(layer "F.SilkS")
		)
		(fp_line
			(start -0.508 -0.9398)
			(end -0.508 0.9398)
			(stroke
				(width 0.1524)
				(type default)
			)
			(layer "F.SilkS")
		)
		(fp_rect
			(start -0.508 0.9398)
			(end 0.508 -0.9398)
			(stroke
				(width 0)
				(type default)
			)
			(fill no)
			(layer "F.CrtYd")
		)
		(fp_rect
			(start -0.508 0.9398)
			(end 0.508 -0.9398)
			(stroke
				(width 0)
				(type default)
			)
			(fill no)
			(layer "F.Fab")
		)
		(pad "1" smd custom
			(at 0 -0.4445 180)
			(size 0.1397 0.1397)
			(layers "F.Cu" "F.Mask" "F.Paste")
			(net "MB3_CM_ADR1_R")
			(options
				(clearance outline)
				(anchor circle)
			)
			(primitives
				(gr_poly
					(pts
						(arc
							(start -0.1778 -0.2794)
							(mid -0.249642 -0.249642)
							(end -0.2794 -0.1778)
						)
						(arc
							(start -0.2794 0.1778)
							(mid -0.249642 0.249642)
							(end -0.1778 0.2794)
						)
						(arc
							(start 0.1778 0.2794)
							(mid 0.249642 0.249642)
							(end 0.2794 0.1778)
						)
						(arc
							(start 0.2794 -0.1778)
							(mid 0.249642 -0.249642)
							(end 0.1778 -0.2794)
						)
					)
					(width 0)
					(fill yes)
				)
			)
		)
		(pad "2" smd custom
			(at 0 0.4445 180)
			(size 0.1397 0.1397)
			(layers "F.Cu" "F.Mask" "F.Paste")
			(net "AGND_CURRENT_DPB")
			(options
				(clearance outline)
				(anchor circle)
			)
			(primitives
				(gr_poly
					(pts
						(arc
							(start -0.1778 -0.2794)
							(mid -0.249642 -0.249642)
							(end -0.2794 -0.1778)
						)
						(arc
							(start -0.2794 0.1778)
							(mid -0.249642 0.249642)
							(end -0.1778 0.2794)
						)
						(arc
							(start 0.1778 0.2794)
							(mid 0.249642 0.249642)
							(end 0.2794 0.1778)
						)
						(arc
							(start 0.2794 -0.1778)
							(mid 0.249642 -0.249642)
							(end 0.1778 -0.2794)
						)
					)
					(width 0)
					(fill yes)
				)
			)
		)
	)
	(footprint ""
		(layer "F.Cu")
		(at 150.136098 -186.287918)
		(property "Reference" "C254"
			(at 0 0 0)
			(layer "F.SilkS")
			(hide yes)
			(effects
				(font
					(size 1.27 1.27)
				)
			)
		)
		(property "Value" "SC4D7U25V5KX-1-GP"
			(at -0.0762 -6.1214 0)
			(unlocked yes)
			(layer "F.Fab")
			(hide yes)
			(effects
				(font
					(size 1.016 1.016)
					(thickness 0.1524)
				)
			)
		)
		(property "Device Type" "C805H58"
			(at -0.0762 -8.1534 0)
			(unlocked yes)
			(layer "F.Fab")
			(hide yes)
			(effects
				(font
					(size 1.016 1.016)
					(thickness 0.1524)
				)
			)
		)
		(duplicate_pad_numbers_are_jumpers no)
		(fp_line
			(start 0.635 0)
			(end -0.635 0)
			(stroke
				(width 0.508)
				(type default)
			)
			(layer "F.SilkS")
		)
		(fp_rect
			(start -0.9652 1.778)
			(end 0.9652 -1.778)
			(stroke
				(width 0)
				(type default)
			)
			(fill no)
			(layer "F.CrtYd")
		)
		(fp_poly
			(pts
				(xy -0.9652 -1.778) (xy 0.9652 -1.778) (xy 0.9652 1.778) (xy -0.9652 1.778)
			)
			(stroke
				(width 0)
				(type default)
			)
			(fill no)
			(layer "F.Fab")
		)
		(pad "1" smd rect
			(at 0 -0.9652)
			(size 1.397 1.143)
			(layers "F.Cu" "F.Mask" "F.Paste")
			(net "P12V_HDD16")
		)
		(pad "2" smd rect
			(at 0 0.9652)
			(size 1.397 1.143)
			(layers "F.Cu" "F.Mask" "F.Paste")
			(net "GND")
		)
	)
	(footprint ""
		(layer "F.Cu")
		(at 149.196298 -278.554942 90)
		(property "Reference" "R235"
			(at 0 0 90)
			(layer "F.SilkS")
			(hide yes)
			(effects
				(font
					(size 1.27 1.27)
				)
			)
		)
		(property "Value" "4K7R2J-2-GP"
			(at 0.064008 -3.993896 90)
			(unlocked yes)
			(layer "F.Fab")
			(hide yes)
			(effects
				(font
					(size 1.016 1.016)
					(thickness 0.1524)
				)
			)
		)
		(property "Device Type" "R402H16"
			(at 0.064008 -5.517896 90)
			(unlocked yes)
			(layer "F.Fab")
			(hide yes)
			(effects
				(font
					(size 1.016 1.016)
					(thickness 0.1524)
				)
			)
		)
		(duplicate_pad_numbers_are_jumpers no)
		(fp_line
			(start 0.508 -0.9398)
			(end -0.508 -0.9398)
			(stroke
				(width 0.1524)
				(type default)
			)
			(layer "F.SilkS")
		)
		(fp_line
			(start -0.508 -0.9398)
			(end -0.508 0.9398)
			(stroke
				(width 0.1524)
				(type default)
			)
			(layer "F.SilkS")
		)
		(fp_rect
			(start -0.508 0.9398)
			(end 0.508 -0.9398)
			(stroke
				(width 0)
				(type default)
			)
			(fill no)
			(layer "F.CrtYd")
		)
		(fp_rect
			(start -0.508 0.9398)
			(end 0.508 -0.9398)
			(stroke
				(width 0)
				(type default)
			)
			(fill no)
			(layer "F.Fab")
		)
		(pad "1" smd custom
			(at 0 -0.4445 90)
			(size 0.1397 0.1397)
			(layers "F.Cu" "F.Mask" "F.Paste")
			(net "SW_PWR_R_HDD4")
			(options
				(clearance outline)
				(anchor circle)
			)
			(primitives
				(gr_poly
					(pts
						(arc
							(start -0.1778 -0.2794)
							(mid -0.249642 -0.249642)
							(end -0.2794 -0.1778)
						)
						(arc
							(start -0.2794 0.1778)
							(mid -0.249642 0.249642)
							(end -0.1778 0.2794)
						)
						(arc
							(start 0.1778 0.2794)
							(mid 0.249642 0.249642)
							(end 0.2794 0.1778)
						)
						(arc
							(start 0.2794 -0.1778)
							(mid 0.249642 -0.249642)
							(end 0.1778 -0.2794)
						)
					)
					(width 0)
					(fill yes)
				)
			)
		)
		(pad "2" smd custom
			(at 0 0.4445 90)
			(size 0.1397 0.1397)
			(layers "F.Cu" "F.Mask" "F.Paste")
			(net "GND")
			(options
				(clearance outline)
				(anchor circle)
			)
			(primitives
				(gr_poly
					(pts
						(arc
							(start -0.1778 -0.2794)
							(mid -0.249642 -0.249642)
							(end -0.2794 -0.1778)
						)
						(arc
							(start -0.2794 0.1778)
							(mid -0.249642 0.249642)
							(end -0.1778 0.2794)
						)
						(arc
							(start 0.1778 0.2794)
							(mid 0.249642 0.249642)
							(end 0.2794 0.1778)
						)
						(arc
							(start 0.2794 -0.1778)
							(mid 0.249642 -0.249642)
							(end 0.1778 -0.2794)
						)
					)
					(width 0)
					(fill yes)
				)
			)
		)
	)
	(footprint ""
		(layer "F.Cu")
		(at 239.50295 -349.162878)
		(property "Reference" "C7"
			(at 0 0 0)
			(layer "F.SilkS")
			(hide yes)
			(effects
				(font
					(size 1.27 1.27)
				)
			)
		)
		(property "Value" "SCD1U16V2KX-3GP"
			(at 1.1811 -2.7051 0)
			(unlocked yes)
			(layer "F.Fab")
			(hide yes)
			(effects
				(font
					(size 1.016 1.016)
					(thickness 0.1524)
				)
			)
		)
		(property "Device Type" "C402H22"
			(at 1.1811 -4.2291 0)
			(unlocked yes)
			(layer "F.Fab")
			(hide yes)
			(effects
				(font
					(size 1.016 1.016)
					(thickness 0.1524)
				)
			)
		)
		(duplicate_pad_numbers_are_jumpers no)
		(fp_rect
			(start -0.4318 0.9525)
			(end 0.4318 -0.9525)
			(stroke
				(width 0)
				(type default)
			)
			(fill no)
			(layer "F.CrtYd")
		)
		(fp_rect
			(start -0.4318 0.9525)
			(end 0.4318 -0.9525)
			(stroke
				(width 0)
				(type default)
			)
			(fill no)
			(layer "F.Fab")
		)
		(pad "1" smd custom
			(at 0 -0.4445)
			(size 0.1524 0.1524)
			(layers "F.Cu" "F.Mask" "F.Paste")
			(net "P5V_A_1_SENSE")
			(options
				(clearance outline)
				(anchor circle)
			)
			(primitives
				(gr_poly
					(pts
						(arc
							(start 0.3048 -0.2032)
							(mid 0.275042 -0.275042)
							(end 0.2032 -0.3048)
						)
						(arc
							(start -0.2032 -0.3048)
							(mid -0.275042 -0.275042)
							(end -0.3048 -0.2032)
						)
						(arc
							(start -0.3048 0.2032)
							(mid -0.275042 0.275042)
							(end -0.2032 0.3048)
						)
						(arc
							(start 0.2032 0.3048)
							(mid 0.275042 0.275042)
							(end 0.3048 0.2032)
						)
					)
					(width 0)
					(fill yes)
				)
			)
		)
		(pad "2" smd custom
			(at 0 0.4445)
			(size 0.1524 0.1524)
			(layers "F.Cu" "F.Mask" "F.Paste")
			(net "GND")
			(options
				(clearance outline)
				(anchor circle)
			)
			(primitives
				(gr_poly
					(pts
						(arc
							(start 0.3048 -0.2032)
							(mid 0.275042 -0.275042)
							(end 0.2032 -0.3048)
						)
						(arc
							(start -0.2032 -0.3048)
							(mid -0.275042 -0.275042)
							(end -0.3048 -0.2032)
						)
						(arc
							(start -0.3048 0.2032)
							(mid -0.275042 0.275042)
							(end -0.2032 0.3048)
						)
						(arc
							(start 0.2032 0.3048)
							(mid 0.275042 0.275042)
							(end 0.3048 0.2032)
						)
					)
					(width 0)
					(fill yes)
				)
			)
		)
	)
	(footprint ""
		(layer "F.Cu")
		(at 240.56975 -349.162878)
		(property "Reference" "R19"
			(at 0 0 0)
			(layer "F.SilkS")
			(hide yes)
			(effects
				(font
					(size 1.27 1.27)
				)
			)
		)
		(property "Value" "10KR2F-2-GP"
			(at 0.064008 -3.993896 0)
			(unlocked yes)
			(layer "F.Fab")
			(hide yes)
			(effects
				(font
					(size 1.016 1.016)
					(thickness 0.1524)
				)
			)
		)
		(property "Device Type" "R402H16"
			(at 0.064008 -5.517896 0)
			(unlocked yes)
			(layer "F.Fab")
			(hide yes)
			(effects
				(font
					(size 1.016 1.016)
					(thickness 0.1524)
				)
			)
		)
		(duplicate_pad_numbers_are_jumpers no)
		(fp_line
			(start -0.508 -0.9398)
			(end -0.508 0.9398)
			(stroke
				(width 0.1524)
				(type default)
			)
			(layer "F.SilkS")
		)
		(fp_line
			(start 0.508 -0.9398)
			(end -0.508 -0.9398)
			(stroke
				(width 0.1524)
				(type default)
			)
			(layer "F.SilkS")
		)
		(fp_rect
			(start -0.508 0.9398)
			(end 0.508 -0.9398)
			(stroke
				(width 0)
				(type default)
			)
			(fill no)
			(layer "F.CrtYd")
		)
		(fp_rect
			(start -0.508 0.9398)
			(end 0.508 -0.9398)
			(stroke
				(width 0)
				(type default)
			)
			(fill no)
			(layer "F.Fab")
		)
		(pad "1" smd custom
			(at 0 -0.4445)
			(size 0.1397 0.1397)
			(layers "F.Cu" "F.Mask" "F.Paste")
			(net "P5V_A_1_SENSE")
			(options
				(clearance outline)
				(anchor circle)
			)
			(primitives
				(gr_poly
					(pts
						(arc
							(start -0.1778 -0.2794)
							(mid -0.249642 -0.249642)
							(end -0.2794 -0.1778)
						)
						(arc
							(start -0.2794 0.1778)
							(mid -0.249642 0.249642)
							(end -0.1778 0.2794)
						)
						(arc
							(start 0.1778 0.2794)
							(mid 0.249642 0.249642)
							(end 0.2794 0.1778)
						)
						(arc
							(start 0.2794 -0.1778)
							(mid 0.249642 -0.249642)
							(end 0.1778 -0.2794)
						)
					)
					(width 0)
					(fill yes)
				)
			)
		)
		(pad "2" smd custom
			(at 0 0.4445)
			(size 0.1397 0.1397)
			(layers "F.Cu" "F.Mask" "F.Paste")
			(net "GND")
			(options
				(clearance outline)
				(anchor circle)
			)
			(primitives
				(gr_poly
					(pts
						(arc
							(start -0.1778 -0.2794)
							(mid -0.249642 -0.249642)
							(end -0.2794 -0.1778)
						)
						(arc
							(start -0.2794 0.1778)
							(mid -0.249642 0.249642)
							(end -0.1778 0.2794)
						)
						(arc
							(start 0.1778 0.2794)
							(mid 0.249642 0.249642)
							(end 0.2794 0.1778)
						)
						(arc
							(start 0.2794 -0.1778)
							(mid 0.249642 -0.249642)
							(end 0.1778 -0.2794)
						)
					)
					(width 0)
					(fill yes)
				)
			)
		)
	)
	(footprint ""
		(layer "F.Cu")
		(at 109.873796 -162.157918 180)
		(property "Reference" "R491"
			(at 0 0 180)
			(layer "F.SilkS")
			(hide yes)
			(effects
				(font
					(size 1.27 1.27)
				)
			)
		)
		(property "Value" "200KR2F-L-GP"
			(at 0.064008 -3.993896 180)
			(unlocked yes)
			(layer "F.Fab")
			(hide yes)
			(effects
				(font
					(size 1.016 1.016)
					(thickness 0.1524)
				)
			)
		)
		(property "Device Type" "R402H16"
			(at 0.064008 -5.517896 180)
			(unlocked yes)
			(layer "F.Fab")
			(hide yes)
			(effects
				(font
					(size 1.016 1.016)
					(thickness 0.1524)
				)
			)
		)
		(duplicate_pad_numbers_are_jumpers no)
		(fp_line
			(start 0.508 -0.9398)
			(end -0.508 -0.9398)
			(stroke
				(width 0.1524)
				(type default)
			)
			(layer "F.SilkS")
		)
		(fp_line
			(start -0.508 -0.9398)
			(end -0.508 0.9398)
			(stroke
				(width 0.1524)
				(type default)
			)
			(layer "F.SilkS")
		)
		(fp_rect
			(start -0.508 0.9398)
			(end 0.508 -0.9398)
			(stroke
				(width 0)
				(type default)
			)
			(fill no)
			(layer "F.CrtYd")
		)
		(fp_rect
			(start -0.508 0.9398)
			(end 0.508 -0.9398)
			(stroke
				(width 0)
				(type default)
			)
			(fill no)
			(layer "F.Fab")
		)
		(pad "1" smd custom
			(at 0 -0.4445 180)
			(size 0.1397 0.1397)
			(layers "F.Cu" "F.Mask" "F.Paste")
			(net "SW_HDD_R15")
			(options
				(clearance outline)
				(anchor circle)
			)
			(primitives
				(gr_poly
					(pts
						(arc
							(start -0.1778 -0.2794)
							(mid -0.249642 -0.249642)
							(end -0.2794 -0.1778)
						)
						(arc
							(start -0.2794 0.1778)
							(mid -0.249642 0.249642)
							(end -0.1778 0.2794)
						)
						(arc
							(start 0.1778 0.2794)
							(mid 0.249642 0.249642)
							(end 0.2794 0.1778)
						)
						(arc
							(start 0.2794 -0.1778)
							(mid 0.249642 -0.249642)
							(end 0.1778 -0.2794)
						)
					)
					(width 0)
					(fill yes)
				)
			)
		)
		(pad "2" smd custom
			(at 0 0.4445 180)
			(size 0.1397 0.1397)
			(layers "F.Cu" "F.Mask" "F.Paste")
			(net "SW_HDD_N15")
			(options
				(clearance outline)
				(anchor circle)
			)
			(primitives
				(gr_poly
					(pts
						(arc
							(start -0.1778 -0.2794)
							(mid -0.249642 -0.249642)
							(end -0.2794 -0.1778)
						)
						(arc
							(start -0.2794 0.1778)
							(mid -0.249642 0.249642)
							(end -0.1778 0.2794)
						)
						(arc
							(start 0.1778 0.2794)
							(mid 0.249642 0.249642)
							(end 0.2794 0.1778)
						)
						(arc
							(start 0.2794 -0.1778)
							(mid 0.249642 -0.249642)
							(end 0.1778 -0.2794)
						)
					)
					(width 0)
					(fill yes)
				)
			)
		)
	)
	(footprint ""
		(layer "F.Cu")
		(at 35.797998 -177.169318 -90)
		(property "Reference" "R406"
			(at 0 0 270)
			(layer "F.SilkS")
			(hide yes)
			(effects
				(font
					(size 1.27 1.27)
				)
			)
		)
		(property "Value" "10KR2F-2-GP"
			(at 0.064008 -3.993896 270)
			(unlocked yes)
			(layer "F.Fab")
			(hide yes)
			(effects
				(font
					(size 1.016 1.016)
					(thickness 0.1524)
				)
			)
		)
		(property "Device Type" "R402H16"
			(at 0.064008 -5.517896 270)
			(unlocked yes)
			(layer "F.Fab")
			(hide yes)
			(effects
				(font
					(size 1.016 1.016)
					(thickness 0.1524)
				)
			)
		)
		(duplicate_pad_numbers_are_jumpers no)
		(fp_line
			(start -0.508 -0.9398)
			(end -0.508 0.9398)
			(stroke
				(width 0.1524)
				(type default)
			)
			(layer "F.SilkS")
		)
		(fp_line
			(start 0.508 -0.9398)
			(end -0.508 -0.9398)
			(stroke
				(width 0.1524)
				(type default)
			)
			(layer "F.SilkS")
		)
		(fp_rect
			(start -0.508 0.9398)
			(end 0.508 -0.9398)
			(stroke
				(width 0)
				(type default)
			)
			(fill no)
			(layer "F.CrtYd")
		)
		(fp_rect
			(start -0.508 0.9398)
			(end 0.508 -0.9398)
			(stroke
				(width 0)
				(type default)
			)
			(fill no)
			(layer "F.Fab")
		)
		(pad "1" smd custom
			(at 0 -0.4445 270)
			(size 0.1397 0.1397)
			(layers "F.Cu" "F.Mask" "F.Paste")
			(net "P3V3_STBY_A")
			(options
				(clearance outline)
				(anchor circle)
			)
			(primitives
				(gr_poly
					(pts
						(arc
							(start -0.1778 -0.2794)
							(mid -0.249642 -0.249642)
							(end -0.2794 -0.1778)
						)
						(arc
							(start -0.2794 0.1778)
							(mid -0.249642 0.249642)
							(end -0.1778 0.2794)
						)
						(arc
							(start 0.1778 0.2794)
							(mid 0.249642 0.249642)
							(end 0.2794 0.1778)
						)
						(arc
							(start 0.2794 -0.1778)
							(mid 0.249642 -0.249642)
							(end 0.1778 -0.2794)
						)
					)
					(width 0)
					(fill yes)
				)
			)
		)
		(pad "2" smd custom
			(at 0 0.4445 270)
			(size 0.1397 0.1397)
			(layers "F.Cu" "F.Mask" "F.Paste")
			(net "HDD_PRSNT_12")
			(options
				(clearance outline)
				(anchor circle)
			)
			(primitives
				(gr_poly
					(pts
						(arc
							(start -0.1778 -0.2794)
							(mid -0.249642 -0.249642)
							(end -0.2794 -0.1778)
						)
						(arc
							(start -0.2794 0.1778)
							(mid -0.249642 0.249642)
							(end -0.1778 0.2794)
						)
						(arc
							(start 0.1778 0.2794)
							(mid 0.249642 0.249642)
							(end 0.2794 0.1778)
						)
						(arc
							(start 0.2794 -0.1778)
							(mid 0.249642 -0.249642)
							(end 0.1778 -0.2794)
						)
					)
					(width 0)
					(fill yes)
				)
			)
		)
	)
	(footprint ""
		(layer "F.Cu")
		(at 419.389052 -277.750016 -90)
		(property "Reference" "VIA22"
			(at 0 0 270)
			(layer "F.SilkS")
			(hide yes)
			(effects
				(font
					(size 1.27 1.27)
				)
			)
		)
		(property "Value" "100OHM-8L-1D6MM-L18L16-GP"
			(at -3.7211 -4.5085 270)
			(unlocked yes)
			(layer "F.Fab")
			(hide yes)
			(effects
				(font
					(size 1.016 1.016)
					(thickness 0.1524)
				)
			)
		)
		(property "Device Type" "VIA-PCIE-4P-394076"
			(at -3.7211 -6.0325 270)
			(unlocked yes)
			(layer "F.Fab")
			(hide yes)
			(effects
				(font
					(size 1.016 1.016)
					(thickness 0.1524)
				)
			)
		)
		(duplicate_pad_numbers_are_jumpers no)
		(fp_rect
			(start -1.9685 0.381)
			(end 1.9685 -0.381)
			(stroke
				(width 0)
				(type default)
			)
			(fill no)
			(layer "F.CrtYd")
		)
		(fp_rect
			(start -1.9685 0.381)
			(end 1.9685 -0.381)
			(stroke
				(width 0)
				(type default)
			)
			(fill no)
			(layer "F.Fab")
		)
		(pad "1" thru_hole circle
			(at -1.5875 0 270)
			(size 0.508 0.508)
			(drill 0.254)
			(layers "*.Cu" "*.Mask")
			(remove_unused_layers no)
			(net "GND")
			(clearance 0.127)
			(thermal_gap 0.127)
		)
		(pad "2" thru_hole circle
			(at -0.5715 0 270)
			(size 0.508 0.508)
			(drill 0.254)
			(layers "*.Cu" "*.Mask")
			(remove_unused_layers no)
			(net "PHY_DRV_A_TO_SCC_A_9_DP")
			(clearance 0.127)
			(thermal_gap 0.127)
		)
		(pad "3" thru_hole circle
			(at 0.5715 0 270)
			(size 0.508 0.508)
			(drill 0.254)
			(layers "*.Cu" "*.Mask")
			(remove_unused_layers no)
			(net "PHY_DRV_A_TO_SCC_A_9_DN")
			(clearance 0.127)
			(thermal_gap 0.127)
		)
		(pad "4" thru_hole circle
			(at 1.5875 0 270)
			(size 0.508 0.508)
			(drill 0.254)
			(layers "*.Cu" "*.Mask")
			(remove_unused_layers no)
			(net "GND")
			(clearance 0.127)
			(thermal_gap 0.127)
		)
	)
)
